# S9S_MB_2U (Grand Teton) — schematic netlist excerpt (pin names and nets, part order shuffled) for the footprints in the layout excerpt that follows; sources: Cadence DE-HDL packaged netlist, KiCad conversion of 03242023_DA0F0TMBIJ0_F0T_Motherboard_J_brd_V01_OCP.brd

R3491  Q_RES  100K 1% EMPTY  pkg 0402LF  page 150 : A = GPU_FPGA_EROT_RECOV_N ; B = GND
R2912  Q_RES  4.7K 5% EMPTY  pkg 0402LF  page 151 : A = P3V3_AUX ; B = FM_GPU_PWR_EN_R1

(kicad_pcb
	(version 20260206)
	(generator "pcbnew")
	(generator_version "10.0")
	(general
		(thickness 1.6)
		(legacy_teardrops no)
	)
	(paper "A4")
	(title_block
		(title "03242023_DA0F0TMBIJ0_F0T_Motherboard_J_brd_V01_OCP.brd")
		(comment 1 "Grand Teton / footprints 1161-1162 of 6105")
	)
	(layers
		(0 "F.Cu" signal "TOP")
		(4 "In1.Cu" signal "GND")
		(6 "In2.Cu" signal "IN1")
		(8 "In3.Cu" signal "GND1")
		(10 "In4.Cu" signal "IN2")
		(12 "In5.Cu" signal "GND2")
		(14 "In6.Cu" signal "IN3")
		(16 "In7.Cu" signal "GND3")
		(18 "In8.Cu" signal "VCC")
		(20 "In9.Cu" signal "VCC1")
		(22 "In10.Cu" signal "GND4")
		(24 "In11.Cu" signal "IN4")
		(26 "In12.Cu" signal "GND5")
		(28 "In13.Cu" signal "IN5")
		(30 "In14.Cu" signal "GND6")
		(32 "In15.Cu" signal "IN6")
		(34 "In16.Cu" signal "GND7")
		(2 "B.Cu" signal "BOTTOM")
		(9 "F.Adhes" user "F.Adhesive")
		(11 "B.Adhes" user "B.Adhesive")
		(13 "F.Paste" user "Package Geometry/Pastemask Top")
		(15 "B.Paste" user "Package Geometry/Pastemask Bottom")
		(5 "F.SilkS" user "Ref Des/Silkscreen Top")
		(7 "B.SilkS" user "Ref Des/Silkscreen Bottom")
		(1 "F.Mask" user "Board Geometry/Soldermask Top")
		(3 "B.Mask" user "Board Geometry/Soldermask Bottom")
		(17 "Dwgs.User" user "User.Drawings")
		(19 "Cmts.User" user "User.Comments")
		(21 "Eco1.User" user "User.Eco1")
		(23 "Eco2.User" user "User.Eco2")
		(25 "Edge.Cuts" user "Board Geometry/Outline")
		(27 "Margin" user)
		(31 "F.CrtYd" user "Package Geometry/Place Bound Top")
		(29 "B.CrtYd" user "Package Geometry/Place Bound Bottom")
		(35 "F.Fab" user "Ref Des/Assembly Top")
		(33 "B.Fab" user "Ref Des/Assembly Bottom")
	)
	(footprint ""
		(layer "F.Cu")
		(at 108.85043 -402.200364 180)
		(property "Reference" "R3491"
			(at 0 0 180)
			(layer "F.SilkS")
			(hide yes)
			(effects
				(font
					(size 1.27 1.27)
				)
			)
		)
		(property "Value" ""
			(at 0 0 180)
			(layer "F.Fab")
			(effects
				(font
					(size 1.27 1.27)
				)
			)
		)
		(duplicate_pad_numbers_are_jumpers no)
		(fp_line
			(start 0.7874 0.4064)
			(end -0.7874 0.4064)
			(stroke
				(width 0.1524)
				(type default)
			)
			(layer "F.SilkS")
		)
		(fp_line
			(start 0.7874 -0.4064)
			(end 0.7874 0.4064)
			(stroke
				(width 0.1524)
				(type default)
			)
			(layer "F.SilkS")
		)
		(fp_line
			(start -0.7874 0.4064)
			(end -0.7874 -0.4064)
			(stroke
				(width 0.1524)
				(type default)
			)
			(layer "F.SilkS")
		)
		(fp_line
			(start -0.7874 -0.4064)
			(end 0.7874 -0.4064)
			(stroke
				(width 0.1524)
				(type default)
			)
			(layer "F.SilkS")
		)
		(fp_line
			(start 0.67945 0.3048)
			(end 0.120396 0.3048)
			(stroke
				(width 0.1)
				(type default)
			)
			(layer "F.Fab")
		)
		(fp_line
			(start 0.67945 -0.3048)
			(end 0.67945 0.3048)
			(stroke
				(width 0.1)
				(type default)
			)
			(layer "F.Fab")
		)
		(fp_line
			(start 0.12065 -0.2794)
			(end 0.12065 -0.3048)
			(stroke
				(width 0.1)
				(type default)
			)
			(layer "F.Fab")
		)
		(fp_line
			(start 0.12065 -0.3048)
			(end 0.67945 -0.3048)
			(stroke
				(width 0.1)
				(type default)
			)
			(layer "F.Fab")
		)
		(fp_line
			(start 0.120396 0.3048)
			(end 0.120396 0.2794)
			(stroke
				(width 0.1)
				(type default)
			)
			(layer "F.Fab")
		)
		(fp_line
			(start 0.120396 0.2794)
			(end -0.12065 0.2794)
			(stroke
				(width 0.1)
				(type default)
			)
			(layer "F.Fab")
		)
		(fp_line
			(start -0.12065 0.3048)
			(end -0.67945 0.3048)
			(stroke
				(width 0.1)
				(type default)
			)
			(layer "F.Fab")
		)
		(fp_line
			(start -0.12065 0.2794)
			(end -0.12065 0.3048)
			(stroke
				(width 0.1)
				(type default)
			)
			(layer "F.Fab")
		)
		(fp_line
			(start -0.12065 -0.2794)
			(end 0.12065 -0.2794)
			(stroke
				(width 0.1)
				(type default)
			)
			(layer "F.Fab")
		)
		(fp_line
			(start -0.12065 -0.305054)
			(end -0.12065 -0.2794)
			(stroke
				(width 0.1)
				(type default)
			)
			(layer "F.Fab")
		)
		(fp_line
			(start -0.67945 0.3048)
			(end -0.67945 -0.305054)
			(stroke
				(width 0.1)
				(type default)
			)
			(layer "F.Fab")
		)
		(fp_line
			(start -0.67945 -0.305054)
			(end -0.12065 -0.305054)
			(stroke
				(width 0.1)
				(type default)
			)
			(layer "F.Fab")
		)
		(pad "1" smd circle
			(at -0.40005 0 180)
			(size 0 0)
			(layers "F.Cu" "F.Mask" "F.Paste")
			(net "GPU_FPGA_EROT_RECOV_N")
		)
		(pad "2" smd circle
			(at 0.40005 0 180)
			(size 0 0)
			(layers "F.Cu" "F.Mask" "F.Paste")
			(net "GND")
		)
	)
	(footprint ""
		(layer "F.Cu")
		(at 120.37822 -422.463468 180)
		(property "Reference" "R2912"
			(at 0 0 180)
			(layer "F.SilkS")
			(hide yes)
			(effects
				(font
					(size 1.27 1.27)
				)
			)
		)
		(property "Value" ""
			(at 0 0 180)
			(layer "F.Fab")
			(effects
				(font
					(size 1.27 1.27)
				)
			)
		)
		(duplicate_pad_numbers_are_jumpers no)
		(fp_line
			(start 0.7874 0.4064)
			(end -0.7874 0.4064)
			(stroke
				(width 0.1524)
				(type default)
			)
			(layer "F.SilkS")
		)
		(fp_line
			(start 0.7874 -0.4064)
			(end 0.7874 0.4064)
			(stroke
				(width 0.1524)
				(type default)
			)
			(layer "F.SilkS")
		)
		(fp_line
			(start -0.7874 0.4064)
			(end -0.7874 -0.4064)
			(stroke
				(width 0.1524)
				(type default)
			)
			(layer "F.SilkS")
		)
		(fp_line
			(start -0.7874 -0.4064)
			(end 0.7874 -0.4064)
			(stroke
				(width 0.1524)
				(type default)
			)
			(layer "F.SilkS")
		)
		(fp_line
			(start 0.67945 0.3048)
			(end 0.120396 0.3048)
			(stroke
				(width 0.1)
				(type default)
			)
			(layer "F.Fab")
		)
		(fp_line
			(start 0.67945 -0.3048)
			(end 0.67945 0.3048)
			(stroke
				(width 0.1)
				(type default)
			)
			(layer "F.Fab")
		)
		(fp_line
			(start 0.12065 -0.2794)
			(end 0.12065 -0.3048)
			(stroke
				(width 0.1)
				(type default)
			)
			(layer "F.Fab")
		)
		(fp_line
			(start 0.12065 -0.3048)
			(end 0.67945 -0.3048)
			(stroke
				(width 0.1)
				(type default)
			)
			(layer "F.Fab")
		)
		(fp_line
			(start 0.120396 0.3048)
			(end 0.120396 0.2794)
			(stroke
				(width 0.1)
				(type default)
			)
			(layer "F.Fab")
		)
		(fp_line
			(start 0.120396 0.2794)
			(end -0.12065 0.2794)
			(stroke
				(width 0.1)
				(type default)
			)
			(layer "F.Fab")
		)
		(fp_line
			(start -0.12065 0.3048)
			(end -0.67945 0.3048)
			(stroke
				(width 0.1)
				(type default)
			)
			(layer "F.Fab")
		)
		(fp_line
			(start -0.12065 0.2794)
			(end -0.12065 0.3048)
			(stroke
				(width 0.1)
				(type default)
			)
			(layer "F.Fab")
		)
		(fp_line
			(start -0.12065 -0.2794)
			(end 0.12065 -0.2794)
			(stroke
				(width 0.1)
				(type default)
			)
			(layer "F.Fab")
		)
		(fp_line
			(start -0.12065 -0.305054)
			(end -0.12065 -0.2794)
			(stroke
				(width 0.1)
				(type default)
			)
			(layer "F.Fab")
		)
		(fp_line
			(start -0.67945 0.3048)
			(end -0.67945 -0.305054)
			(stroke
				(width 0.1)
				(type default)
			)
			(layer "F.Fab")
		)
		(fp_line
			(start -0.67945 -0.305054)
			(end -0.12065 -0.305054)
			(stroke
				(width 0.1)
				(type default)
			)
			(layer "F.Fab")
		)
		(pad "1" smd circle
			(at -0.40005 0 180)
			(size 0 0)
			(layers "F.Cu" "F.Mask" "F.Paste")
			(net "P3V3_AUX")
		)
		(pad "2" smd circle
			(at 0.40005 0 180)
			(size 0 0)
			(layers "F.Cu" "F.Mask" "F.Paste")
			(net "FM_GPU_PWR_EN_R1")
		)
	)
)
